# T6G (Grand Teton) — schematic netlist excerpt (pin names and nets, part order shuffled) for the footprints in the layout excerpt that follows; sources: Cadence DE-HDL packaged netlist, KiCad conversion of 04192023_DAF0TMB3IC0_F0TG_MB_C_brd_V02_OCP.brd

C9226  Q_CAP  0.22UF 25V 10% X7R  pkg C0402  page 188 : A = VR_P5V_EN_D_R ; B = GND
R8002  Q_RES  4.7K 5% CHIP  pkg 0402LF  page 123 : A = P3V3_AUX ; B = PRSNT_SWB

(kicad_pcb
	(version 20260206)
	(generator "pcbnew")
	(generator_version "10.0")
	(general
		(thickness 1.6)
		(legacy_teardrops no)
	)
	(paper "A4")
	(title_block
		(title "04192023_DAF0TMB3IC0_F0TG_MB_C_brd_V02_OCP.brd")
		(comment 1 "Grand Teton / footprints 5208-5209 of 8354")
	)
	(layers
		(0 "F.Cu" signal "TOP")
		(4 "In1.Cu" signal "GND")
		(6 "In2.Cu" signal "IN1")
		(8 "In3.Cu" signal "GND1")
		(10 "In4.Cu" signal "IN2")
		(12 "In5.Cu" signal "GND2")
		(14 "In6.Cu" signal "IN3")
		(16 "In7.Cu" signal "GND3")
		(18 "In8.Cu" signal "VCC")
		(20 "In9.Cu" signal "VCC1")
		(22 "In10.Cu" signal "GND4")
		(24 "In11.Cu" signal "IN4")
		(26 "In12.Cu" signal "GND5")
		(28 "In13.Cu" signal "IN5")
		(30 "In14.Cu" signal "GND6")
		(32 "In15.Cu" signal "IN6")
		(34 "In16.Cu" signal "GND7")
		(2 "B.Cu" signal "BOTTOM")
		(9 "F.Adhes" user "F.Adhesive")
		(11 "B.Adhes" user "B.Adhesive")
		(13 "F.Paste" user "Package Geometry/Pastemask Top")
		(15 "B.Paste" user "Package Geometry/Pastemask Bottom")
		(5 "F.SilkS" user "Ref Des/Silkscreen Top")
		(7 "B.SilkS" user "Ref Des/Silkscreen Bottom")
		(1 "F.Mask" user "Board Geometry/Soldermask Top")
		(3 "B.Mask" user "Board Geometry/Soldermask Bottom")
		(17 "Dwgs.User" user "User.Drawings")
		(19 "Cmts.User" user "User.Comments")
		(21 "Eco1.User" user "User.Eco1")
		(23 "Eco2.User" user "User.Eco2")
		(25 "Edge.Cuts" user "Board Geometry/Outline")
		(27 "Margin" user)
		(31 "F.CrtYd" user "Package Geometry/Place Bound Top")
		(29 "B.CrtYd" user "Package Geometry/Place Bound Bottom")
		(35 "F.Fab" user "Ref Des/Assembly Top")
		(33 "B.Fab" user "Ref Des/Assembly Bottom")
	)
	(footprint ""
		(layer "B.Cu")
		(at 104.521 -424.815)
		(property "Reference" "R8002"
			(at 0 0 0)
			(layer "B.SilkS")
			(hide yes)
			(effects
				(font
					(size 1.27 1.27)
				)
				(justify mirror)
			)
		)
		(property "Value" ""
			(at 0 0 0)
			(layer "B.Fab")
			(effects
				(font
					(size 1.27 1.27)
				)
				(justify mirror)
			)
		)
		(duplicate_pad_numbers_are_jumpers no)
		(fp_line
			(start -0.7874 -0.4064)
			(end -0.7874 0.4064)
			(stroke
				(width 0.1524)
				(type default)
			)
			(layer "B.SilkS")
		)
		(fp_line
			(start -0.7874 0.4064)
			(end 0.7874 0.4064)
			(stroke
				(width 0.1524)
				(type default)
			)
			(layer "B.SilkS")
		)
		(fp_line
			(start 0.7874 -0.4064)
			(end -0.7874 -0.4064)
			(stroke
				(width 0.1524)
				(type default)
			)
			(layer "B.SilkS")
		)
		(fp_line
			(start 0.7874 0.4064)
			(end 0.7874 -0.4064)
			(stroke
				(width 0.1524)
				(type default)
			)
			(layer "B.SilkS")
		)
		(fp_line
			(start -0.67945 -0.3048)
			(end -0.67945 0.3048)
			(stroke
				(width 0.1)
				(type default)
			)
			(layer "B.Fab")
		)
		(fp_line
			(start -0.67945 0.3048)
			(end -0.120396 0.3048)
			(stroke
				(width 0.1)
				(type default)
			)
			(layer "B.Fab")
		)
		(fp_line
			(start -0.12065 -0.3048)
			(end -0.67945 -0.3048)
			(stroke
				(width 0.1)
				(type default)
			)
			(layer "B.Fab")
		)
		(fp_line
			(start -0.12065 -0.2794)
			(end -0.12065 -0.3048)
			(stroke
				(width 0.1)
				(type default)
			)
			(layer "B.Fab")
		)
		(fp_line
			(start -0.120396 0.2794)
			(end 0.12065 0.2794)
			(stroke
				(width 0.1)
				(type default)
			)
			(layer "B.Fab")
		)
		(fp_line
			(start -0.120396 0.3048)
			(end -0.120396 0.2794)
			(stroke
				(width 0.1)
				(type default)
			)
			(layer "B.Fab")
		)
		(fp_line
			(start 0.12065 -0.305054)
			(end 0.12065 -0.2794)
			(stroke
				(width 0.1)
				(type default)
			)
			(layer "B.Fab")
		)
		(fp_line
			(start 0.12065 -0.2794)
			(end -0.12065 -0.2794)
			(stroke
				(width 0.1)
				(type default)
			)
			(layer "B.Fab")
		)
		(fp_line
			(start 0.12065 0.2794)
			(end 0.12065 0.3048)
			(stroke
				(width 0.1)
				(type default)
			)
			(layer "B.Fab")
		)
		(fp_line
			(start 0.12065 0.3048)
			(end 0.67945 0.3048)
			(stroke
				(width 0.1)
				(type default)
			)
			(layer "B.Fab")
		)
		(fp_line
			(start 0.67945 -0.305054)
			(end 0.12065 -0.305054)
			(stroke
				(width 0.1)
				(type default)
			)
			(layer "B.Fab")
		)
		(fp_line
			(start 0.67945 0.3048)
			(end 0.67945 -0.305054)
			(stroke
				(width 0.1)
				(type default)
			)
			(layer "B.Fab")
		)
		(pad "1" smd circle
			(at 0.40005 0 180)
			(size 0 0)
			(layers "B.Cu" "B.Mask" "B.Paste")
			(net "P3V3_AUX")
		)
		(pad "2" smd circle
			(at -0.40005 0 180)
			(size 0 0)
			(layers "B.Cu" "B.Mask" "B.Paste")
			(net "PRSNT_SWB")
		)
	)
	(footprint ""
		(layer "B.Cu")
		(at 398.230344 -145.401538 90)
		(property "Reference" "C9226"
			(at 0 0 90)
			(layer "B.SilkS")
			(hide yes)
			(effects
				(font
					(size 1.27 1.27)
				)
				(justify mirror)
			)
		)
		(property "Value" ""
			(at 0 0 90)
			(layer "B.Fab")
			(effects
				(font
					(size 1.27 1.27)
				)
				(justify mirror)
			)
		)
		(duplicate_pad_numbers_are_jumpers no)
		(fp_line
			(start 0.7874 -0.4064)
			(end -0.7874 -0.4064)
			(stroke
				(width 0.1524)
				(type default)
			)
			(layer "B.SilkS")
		)
		(fp_line
			(start -0.7874 -0.4064)
			(end -0.7874 0.4064)
			(stroke
				(width 0.1524)
				(type default)
			)
			(layer "B.SilkS")
		)
		(fp_line
			(start 0.7874 0.4064)
			(end 0.7874 -0.4064)
			(stroke
				(width 0.1524)
				(type default)
			)
			(layer "B.SilkS")
		)
		(fp_line
			(start -0.7874 0.4064)
			(end 0.7874 0.4064)
			(stroke
				(width 0.1524)
				(type default)
			)
			(layer "B.SilkS")
		)
		(fp_line
			(start 0.67945 -0.305054)
			(end 0.12065 -0.305054)
			(stroke
				(width 0.1)
				(type default)
			)
			(layer "B.Fab")
		)
		(fp_line
			(start 0.12065 -0.305054)
			(end 0.12065 -0.2794)
			(stroke
				(width 0.1)
				(type default)
			)
			(layer "B.Fab")
		)
		(fp_line
			(start -0.12065 -0.3048)
			(end -0.67945 -0.3048)
			(stroke
				(width 0.1)
				(type default)
			)
			(layer "B.Fab")
		)
		(fp_line
			(start -0.67945 -0.3048)
			(end -0.67945 0.3048)
			(stroke
				(width 0.1)
				(type default)
			)
			(layer "B.Fab")
		)
		(fp_line
			(start 0.12065 -0.2794)
			(end -0.12065 -0.2794)
			(stroke
				(width 0.1)
				(type default)
			)
			(layer "B.Fab")
		)
		(fp_line
			(start -0.12065 -0.2794)
			(end -0.12065 -0.3048)
			(stroke
				(width 0.1)
				(type default)
			)
			(layer "B.Fab")
		)
		(fp_line
			(start 0.12065 0.2794)
			(end 0.12065 0.3048)
			(stroke
				(width 0.1)
				(type default)
			)
			(layer "B.Fab")
		)
		(fp_line
			(start -0.120396 0.2794)
			(end 0.12065 0.2794)
			(stroke
				(width 0.1)
				(type default)
			)
			(layer "B.Fab")
		)
		(fp_line
			(start 0.67945 0.3048)
			(end 0.67945 -0.305054)
			(stroke
				(width 0.1)
				(type default)
			)
			(layer "B.Fab")
		)
		(fp_line
			(start 0.12065 0.3048)
			(end 0.67945 0.3048)
			(stroke
				(width 0.1)
				(type default)
			)
			(layer "B.Fab")
		)
		(fp_line
			(start -0.120396 0.3048)
			(end -0.120396 0.2794)
			(stroke
				(width 0.1)
				(type default)
			)
			(layer "B.Fab")
		)
		(fp_line
			(start -0.67945 0.3048)
			(end -0.120396 0.3048)
			(stroke
				(width 0.1)
				(type default)
			)
			(layer "B.Fab")
		)
		(pad "1" smd circle
			(at 0.40005 0 270)
			(size 0 0)
			(layers "B.Cu" "B.Mask" "B.Paste")
			(net "VR_P5V_EN_D_R")
		)
		(pad "2" smd circle
			(at -0.40005 0 270)
			(size 0 0)
			(layers "B.Cu" "B.Mask" "B.Paste")
			(net "GND")
		)
	)
)
